# SCM (Grand Teton) — schematic netlist excerpt (pin names and nets, part order shuffled) for the footprints in the layout excerpt that follows; sources: Cadence DE-HDL packaged netlist, KiCad conversion of 12092022_DA0F0TMDCD0_F0T_Management_Board_D_brd_V3_OCP.brd

C236  Q_CAP  0.1UF 25V 10% X7R  pkg 0402  page 29 : A = P3V3_AUX ; B = GND
R258  Q_RES  2.2K 5% CHIP  pkg 0402LF  page 27 : A = P3V3_AUX ; B = SMB_BMC_MM8_SCL
C330  Q_CAP  22UF 16V 20% X6S  pkg C0805  page 10 : A = P12V_AUX ; B = GND

(kicad_pcb
	(version 20260206)
	(generator "pcbnew")
	(generator_version "10.0")
	(general
		(thickness 1.6)
		(legacy_teardrops no)
	)
	(paper "A4")
	(title_block
		(title "12092022_DA0F0TMDCD0_F0T_Management_Board_D_brd_V3_OCP.brd")
		(comment 1 "Grand Teton / footprints 1267-1269 of 1440")
	)
	(layers
		(0 "F.Cu" signal "TOP")
		(4 "In1.Cu" signal "GND")
		(6 "In2.Cu" signal "IN1")
		(8 "In3.Cu" signal "GND1")
		(10 "In4.Cu" signal "IN2")
		(12 "In5.Cu" signal "VCC")
		(14 "In6.Cu" signal "VCC1")
		(16 "In7.Cu" signal "IN3")
		(18 "In8.Cu" signal "GND2")
		(20 "In9.Cu" signal "IN4")
		(22 "In10.Cu" signal "GND3")
		(2 "B.Cu" signal "BOTTOM")
		(9 "F.Adhes" user "F.Adhesive")
		(11 "B.Adhes" user "B.Adhesive")
		(13 "F.Paste" user "Package Geometry/Pastemask Top")
		(15 "B.Paste" user "Package Geometry/Pastemask Bottom")
		(5 "F.SilkS" user "Ref Des/Silkscreen Top")
		(7 "B.SilkS" user "Ref Des/Silkscreen Bottom")
		(1 "F.Mask" user "Board Geometry/Soldermask Top")
		(3 "B.Mask" user "Board Geometry/Soldermask Bottom")
		(17 "Dwgs.User" user "User.Drawings")
		(19 "Cmts.User" user "User.Comments")
		(21 "Eco1.User" user "User.Eco1")
		(23 "Eco2.User" user "User.Eco2")
		(25 "Edge.Cuts" user "Board Geometry/Outline")
		(27 "Margin" user)
		(31 "F.CrtYd" user "Package Geometry/Place Bound Top")
		(29 "B.CrtYd" user "Package Geometry/Place Bound Bottom")
		(35 "F.Fab" user "Ref Des/Assembly Top")
		(33 "B.Fab" user "Ref Des/Assembly Bottom")
	)
	(footprint ""
		(layer "B.Cu")
		(at 55.705502 -30.867604 -90)
		(property "Reference" "R258"
			(at 0 0 90)
			(layer "B.SilkS")
			(hide yes)
			(effects
				(font
					(size 1.27 1.27)
				)
				(justify mirror)
			)
		)
		(property "Value" ""
			(at 0 0 90)
			(layer "B.Fab")
			(effects
				(font
					(size 1.27 1.27)
				)
				(justify mirror)
			)
		)
		(duplicate_pad_numbers_are_jumpers no)
		(fp_line
			(start -0.7874 0.4064)
			(end 0.7874 0.4064)
			(stroke
				(width 0.1524)
				(type default)
			)
			(layer "B.SilkS")
		)
		(fp_line
			(start 0.7874 0.4064)
			(end 0.7874 -0.4064)
			(stroke
				(width 0.1524)
				(type default)
			)
			(layer "B.SilkS")
		)
		(fp_line
			(start -0.7874 -0.4064)
			(end -0.7874 0.4064)
			(stroke
				(width 0.1524)
				(type default)
			)
			(layer "B.SilkS")
		)
		(fp_line
			(start 0.7874 -0.4064)
			(end -0.7874 -0.4064)
			(stroke
				(width 0.1524)
				(type default)
			)
			(layer "B.SilkS")
		)
		(fp_line
			(start -0.67945 0.3048)
			(end -0.120396 0.3048)
			(stroke
				(width 0.1)
				(type default)
			)
			(layer "B.Fab")
		)
		(fp_line
			(start -0.120396 0.3048)
			(end -0.120396 0.2794)
			(stroke
				(width 0.1)
				(type default)
			)
			(layer "B.Fab")
		)
		(fp_line
			(start 0.12065 0.3048)
			(end 0.67945 0.3048)
			(stroke
				(width 0.1)
				(type default)
			)
			(layer "B.Fab")
		)
		(fp_line
			(start 0.67945 0.3048)
			(end 0.67945 -0.305054)
			(stroke
				(width 0.1)
				(type default)
			)
			(layer "B.Fab")
		)
		(fp_line
			(start -0.120396 0.2794)
			(end 0.12065 0.2794)
			(stroke
				(width 0.1)
				(type default)
			)
			(layer "B.Fab")
		)
		(fp_line
			(start 0.12065 0.2794)
			(end 0.12065 0.3048)
			(stroke
				(width 0.1)
				(type default)
			)
			(layer "B.Fab")
		)
		(fp_line
			(start -0.12065 -0.2794)
			(end -0.12065 -0.3048)
			(stroke
				(width 0.1)
				(type default)
			)
			(layer "B.Fab")
		)
		(fp_line
			(start 0.12065 -0.2794)
			(end -0.12065 -0.2794)
			(stroke
				(width 0.1)
				(type default)
			)
			(layer "B.Fab")
		)
		(fp_line
			(start -0.67945 -0.3048)
			(end -0.67945 0.3048)
			(stroke
				(width 0.1)
				(type default)
			)
			(layer "B.Fab")
		)
		(fp_line
			(start -0.12065 -0.3048)
			(end -0.67945 -0.3048)
			(stroke
				(width 0.1)
				(type default)
			)
			(layer "B.Fab")
		)
		(fp_line
			(start 0.12065 -0.305054)
			(end 0.12065 -0.2794)
			(stroke
				(width 0.1)
				(type default)
			)
			(layer "B.Fab")
		)
		(fp_line
			(start 0.67945 -0.305054)
			(end 0.12065 -0.305054)
			(stroke
				(width 0.1)
				(type default)
			)
			(layer "B.Fab")
		)
		(pad "1" smd circle
			(at 0.40005 0 90)
			(size 0 0)
			(layers "B.Cu" "B.Mask" "B.Paste")
			(net "P3V3_AUX")
		)
		(pad "2" smd circle
			(at -0.40005 0 90)
			(size 0 0)
			(layers "B.Cu" "B.Mask" "B.Paste")
			(net "SMB_BMC_MM8_SCL")
		)
	)
	(footprint ""
		(layer "B.Cu")
		(at 37.6047 -92.2528 -90)
		(property "Reference" "C236"
			(at 0 0 90)
			(layer "B.SilkS")
			(hide yes)
			(effects
				(font
					(size 1.27 1.27)
				)
				(justify mirror)
			)
		)
		(property "Value" ""
			(at 0 0 90)
			(layer "B.Fab")
			(effects
				(font
					(size 1.27 1.27)
				)
				(justify mirror)
			)
		)
		(duplicate_pad_numbers_are_jumpers no)
		(fp_line
			(start -0.7874 0.4064)
			(end 0.7874 0.4064)
			(stroke
				(width 0.1524)
				(type default)
			)
			(layer "B.SilkS")
		)
		(fp_line
			(start 0.7874 0.4064)
			(end 0.7874 -0.4064)
			(stroke
				(width 0.1524)
				(type default)
			)
			(layer "B.SilkS")
		)
		(fp_line
			(start -0.7874 -0.4064)
			(end -0.7874 0.4064)
			(stroke
				(width 0.1524)
				(type default)
			)
			(layer "B.SilkS")
		)
		(fp_line
			(start 0.7874 -0.4064)
			(end -0.7874 -0.4064)
			(stroke
				(width 0.1524)
				(type default)
			)
			(layer "B.SilkS")
		)
		(fp_line
			(start -0.67945 0.3048)
			(end -0.120396 0.3048)
			(stroke
				(width 0.1)
				(type default)
			)
			(layer "B.Fab")
		)
		(fp_line
			(start -0.120396 0.3048)
			(end -0.120396 0.2794)
			(stroke
				(width 0.1)
				(type default)
			)
			(layer "B.Fab")
		)
		(fp_line
			(start 0.12065 0.3048)
			(end 0.67945 0.3048)
			(stroke
				(width 0.1)
				(type default)
			)
			(layer "B.Fab")
		)
		(fp_line
			(start 0.67945 0.3048)
			(end 0.67945 -0.305054)
			(stroke
				(width 0.1)
				(type default)
			)
			(layer "B.Fab")
		)
		(fp_line
			(start -0.120396 0.2794)
			(end 0.12065 0.2794)
			(stroke
				(width 0.1)
				(type default)
			)
			(layer "B.Fab")
		)
		(fp_line
			(start 0.12065 0.2794)
			(end 0.12065 0.3048)
			(stroke
				(width 0.1)
				(type default)
			)
			(layer "B.Fab")
		)
		(fp_line
			(start -0.12065 -0.2794)
			(end -0.12065 -0.3048)
			(stroke
				(width 0.1)
				(type default)
			)
			(layer "B.Fab")
		)
		(fp_line
			(start 0.12065 -0.2794)
			(end -0.12065 -0.2794)
			(stroke
				(width 0.1)
				(type default)
			)
			(layer "B.Fab")
		)
		(fp_line
			(start -0.67945 -0.3048)
			(end -0.67945 0.3048)
			(stroke
				(width 0.1)
				(type default)
			)
			(layer "B.Fab")
		)
		(fp_line
			(start -0.12065 -0.3048)
			(end -0.67945 -0.3048)
			(stroke
				(width 0.1)
				(type default)
			)
			(layer "B.Fab")
		)
		(fp_line
			(start 0.12065 -0.305054)
			(end 0.12065 -0.2794)
			(stroke
				(width 0.1)
				(type default)
			)
			(layer "B.Fab")
		)
		(fp_line
			(start 0.67945 -0.305054)
			(end 0.12065 -0.305054)
			(stroke
				(width 0.1)
				(type default)
			)
			(layer "B.Fab")
		)
		(pad "1" smd circle
			(at 0.40005 0 90)
			(size 0 0)
			(layers "B.Cu" "B.Mask" "B.Paste")
			(net "P3V3_AUX")
		)
		(pad "2" smd circle
			(at -0.40005 0 90)
			(size 0 0)
			(layers "B.Cu" "B.Mask" "B.Paste")
			(net "GND")
		)
	)
	(footprint ""
		(layer "B.Cu")
		(at 83.058 -101.473 90)
		(property "Reference" "C330"
			(at 0 0 90)
			(layer "B.SilkS")
			(hide yes)
			(effects
				(font
					(size 1.27 1.27)
				)
				(justify mirror)
			)
		)
		(property "Value" ""
			(at 0 0 90)
			(layer "B.Fab")
			(effects
				(font
					(size 1.27 1.27)
				)
				(justify mirror)
			)
		)
		(duplicate_pad_numbers_are_jumpers no)
		(fp_line
			(start 1.524 -0.762)
			(end -1.524 -0.762)
			(stroke
				(width 0.1524)
				(type default)
			)
			(layer "B.SilkS")
		)
		(fp_line
			(start -1.524 -0.762)
			(end -1.524 0.762)
			(stroke
				(width 0.1524)
				(type default)
			)
			(layer "B.SilkS")
		)
		(fp_line
			(start 1.524 0.762)
			(end 1.524 -0.762)
			(stroke
				(width 0.1524)
				(type default)
			)
			(layer "B.SilkS")
		)
		(fp_line
			(start -1.524 0.762)
			(end 1.524 0.762)
			(stroke
				(width 0.1524)
				(type default)
			)
			(layer "B.SilkS")
		)
		(fp_line
			(start 1.1049 -0.724916)
			(end 1.1049 0.724916)
			(stroke
				(width 0.1)
				(type default)
			)
			(layer "B.Fab")
		)
		(fp_line
			(start -1.1049 -0.724916)
			(end 1.1049 -0.724916)
			(stroke
				(width 0.1)
				(type default)
			)
			(layer "B.Fab")
		)
		(fp_line
			(start 1.1049 0.724916)
			(end -1.1049 0.724916)
			(stroke
				(width 0.1)
				(type default)
			)
			(layer "B.Fab")
		)
		(fp_line
			(start -1.1049 0.724916)
			(end -1.1049 -0.724916)
			(stroke
				(width 0.1)
				(type default)
			)
			(layer "B.Fab")
		)
		(pad "1" smd rect
			(at 0.889 0 90)
			(size 1.016 1.27)
			(layers "B.Cu" "B.Mask" "B.Paste")
			(net "P12V_AUX")
		)
		(pad "2" smd rect
			(at -0.889 0 90)
			(size 1.016 1.27)
			(layers "B.Cu" "B.Mask" "B.Paste")
			(net "GND")
		)
	)
)
